FILE_TYPE=LIBRARY_PARTS;
primitive 'CONN1_10165288101LF';
  pin
    'NC1':
      PIN_NUMBER='(SCR_H1)';
      BIDIRECTIONAL='TRUE';
      INPUT_LOAD='(-0.01,0.01)';
      OUTPUT_LOAD='(1.0,-1.0)';
  end_pin;
  body
    PART_NAME='CONN1_10165288101LF';
    BODY_NAME='CONN1_10165288101LF';
    PHYS_DES_PREFIX='J';
    CLASS='IO';
    NC_PINS='(H1,H2)';
  end_body;
end_primitive;

END.
